FILE_TYPE = CONNECTIVITY;
{Allegro Design Entry HDL 17.2-2016 S081 (4005846) 1/11/2022}
"PAGE_NUMBER" = 24;
0"NC";
END.
